(kicad_pcb
	(version 20260206)
	(generator "pcbnew")
	(generator_version "10.0")
	(general
		(thickness 1.6)
		(legacy_teardrops no)
	)
	(paper "A4")
	(title_block
		(title "baseboard — 13948-1b.1110WZS1818.brd")
		(comment 1 "Honey Badger (Wiwynn) / footprints 1350-1357 of 2523")
	)
	(layers
		(0 "F.Cu" signal "TOP")
		(4 "In1.Cu" signal "L2GND")
		(6 "In2.Cu" signal "L3")
		(8 "In3.Cu" signal "L4VCC")
		(10 "In4.Cu" signal "L5VCC")
		(12 "In5.Cu" signal "L6")
		(14 "In6.Cu" signal "L7GND")
		(2 "B.Cu" signal "BOTTOM")
		(9 "F.Adhes" user "F.Adhesive")
		(11 "B.Adhes" user "B.Adhesive")
		(13 "F.Paste" user "Package Geometry/Pastemask Top")
		(15 "B.Paste" user "Package Geometry/Pastemask Bottom")
		(5 "F.SilkS" user "Ref Des/Silkscreen Top")
		(7 "B.SilkS" user "Ref Des/Silkscreen Bottom")
		(1 "F.Mask" user "Board Geometry/Soldermask Top")
		(3 "B.Mask" user "Board Geometry/Soldermask Bottom")
		(17 "Dwgs.User" user "User.Drawings")
		(19 "Cmts.User" user "User.Comments")
		(21 "Eco1.User" user "User.Eco1")
		(23 "Eco2.User" user "User.Eco2")
		(25 "Edge.Cuts" user "Board Geometry/Outline")
		(27 "Margin" user)
		(31 "F.CrtYd" user "Package Geometry/Place Bound Top")
		(29 "B.CrtYd" user "Package Geometry/Place Bound Bottom")
		(35 "F.Fab" user "Ref Des/Assembly Top")
		(33 "B.Fab" user "Ref Des/Assembly Bottom")
	)
	(footprint ""
		(layer "F.Cu")
		(at 319.913 -146.558 90)
		(property "Reference" "R655"
			(at 0 0 90)
			(layer "F.SilkS")
			(hide yes)
			(effects
				(font
					(size 1.27 1.27)
				)
			)
		)
		(property "Value" "4K7R2F-GP"
			(at 0.064008 -3.993896 90)
			(unlocked yes)
			(layer "F.Fab")
			(hide yes)
			(effects
				(font
					(size 1.016 1.016)
					(thickness 0.1524)
				)
			)
		)
		(property "Device Type" "R402H16"
			(at 0.064008 -5.517896 90)
			(unlocked yes)
			(layer "F.Fab")
			(hide yes)
			(effects
				(font
					(size 1.016 1.016)
					(thickness 0.1524)
				)
			)
		)
		(duplicate_pad_numbers_are_jumpers no)
		(fp_line
			(start 0.508 -0.9398)
			(end -0.508 -0.9398)
			(stroke
				(width 0.1524)
				(type default)
			)
			(layer "F.SilkS")
		)
		(fp_line
			(start -0.508 -0.9398)
			(end -0.508 0.9398)
			(stroke
				(width 0.1524)
				(type default)
			)
			(layer "F.SilkS")
		)
		(fp_rect
			(start -0.508 0.9398)
			(end 0.508 -0.9398)
			(stroke
				(width 0)
				(type default)
			)
			(fill no)
			(layer "F.CrtYd")
		)
		(fp_rect
			(start -0.508 0.9398)
			(end 0.508 -0.9398)
			(stroke
				(width 0)
				(type default)
			)
			(fill no)
			(layer "F.Fab")
		)
		(pad "1" smd custom
			(at 0 -0.4445 90)
			(size 0.1397 0.1397)
			(layers "F.Cu" "F.Mask" "F.Paste")
			(net "P3V3_RTC")
			(options
				(clearance outline)
				(anchor circle)
			)
			(primitives
				(gr_poly
					(pts
						(arc
							(start -0.1778 -0.2794)
							(mid -0.249642 -0.249642)
							(end -0.2794 -0.1778)
						)
						(arc
							(start -0.2794 0.1778)
							(mid -0.249642 0.249642)
							(end -0.1778 0.2794)
						)
						(arc
							(start 0.1778 0.2794)
							(mid 0.249642 0.249642)
							(end 0.2794 0.1778)
						)
						(arc
							(start 0.2794 -0.1778)
							(mid 0.249642 -0.249642)
							(end 0.1778 -0.2794)
						)
					)
					(width 0)
					(fill yes)
				)
			)
		)
		(pad "2" smd custom
			(at 0 0.4445 90)
			(size 0.1397 0.1397)
			(layers "F.Cu" "F.Mask" "F.Paste")
			(net "RTC_INT_N")
			(options
				(clearance outline)
				(anchor circle)
			)
			(primitives
				(gr_poly
					(pts
						(arc
							(start -0.1778 -0.2794)
							(mid -0.249642 -0.249642)
							(end -0.2794 -0.1778)
						)
						(arc
							(start -0.2794 0.1778)
							(mid -0.249642 0.249642)
							(end -0.1778 0.2794)
						)
						(arc
							(start 0.1778 0.2794)
							(mid 0.249642 0.249642)
							(end 0.2794 0.1778)
						)
						(arc
							(start 0.2794 -0.1778)
							(mid 0.249642 -0.249642)
							(end 0.1778 -0.2794)
						)
					)
					(width 0)
					(fill yes)
				)
			)
		)
	)
	(footprint ""
		(layer "F.Cu")
		(at 68.834 -224.663 -90)
		(property "Reference" "R2115"
			(at 0 0 270)
			(layer "F.SilkS")
			(hide yes)
			(effects
				(font
					(size 1.27 1.27)
				)
			)
		)
		(property "Value" "0R2J-2-GP"
			(at 0.064008 -3.993896 270)
			(unlocked yes)
			(layer "F.Fab")
			(hide yes)
			(effects
				(font
					(size 1.016 1.016)
					(thickness 0.1524)
				)
			)
		)
		(property "Device Type" "R402H16"
			(at 0.064008 -5.517896 270)
			(unlocked yes)
			(layer "F.Fab")
			(hide yes)
			(effects
				(font
					(size 1.016 1.016)
					(thickness 0.1524)
				)
			)
		)
		(duplicate_pad_numbers_are_jumpers no)
		(fp_line
			(start -0.508 -0.9398)
			(end -0.508 0.9398)
			(stroke
				(width 0.1524)
				(type default)
			)
			(layer "F.SilkS")
		)
		(fp_line
			(start 0.508 -0.9398)
			(end -0.508 -0.9398)
			(stroke
				(width 0.1524)
				(type default)
			)
			(layer "F.SilkS")
		)
		(fp_rect
			(start -0.508 0.9398)
			(end 0.508 -0.9398)
			(stroke
				(width 0)
				(type default)
			)
			(fill no)
			(layer "F.CrtYd")
		)
		(fp_rect
			(start -0.508 0.9398)
			(end 0.508 -0.9398)
			(stroke
				(width 0)
				(type default)
			)
			(fill no)
			(layer "F.Fab")
		)
		(pad "1" smd custom
			(at 0 -0.4445 270)
			(size 0.1397 0.1397)
			(layers "F.Cu" "F.Mask" "F.Paste")
			(net "MB0_P12V_R")
			(options
				(clearance outline)
				(anchor circle)
			)
			(primitives
				(gr_poly
					(pts
						(arc
							(start -0.1778 -0.2794)
							(mid -0.249642 -0.249642)
							(end -0.2794 -0.1778)
						)
						(arc
							(start -0.2794 0.1778)
							(mid -0.249642 0.249642)
							(end -0.1778 0.2794)
						)
						(arc
							(start 0.1778 0.2794)
							(mid 0.249642 0.249642)
							(end 0.2794 0.1778)
						)
						(arc
							(start 0.2794 -0.1778)
							(mid 0.249642 -0.249642)
							(end 0.1778 -0.2794)
						)
					)
					(width 0)
					(fill yes)
				)
			)
		)
		(pad "2" smd custom
			(at 0 0.4445 270)
			(size 0.1397 0.1397)
			(layers "F.Cu" "F.Mask" "F.Paste")
			(net "P12V")
			(options
				(clearance outline)
				(anchor circle)
			)
			(primitives
				(gr_poly
					(pts
						(arc
							(start -0.1778 -0.2794)
							(mid -0.249642 -0.249642)
							(end -0.2794 -0.1778)
						)
						(arc
							(start -0.2794 0.1778)
							(mid -0.249642 0.249642)
							(end -0.1778 0.2794)
						)
						(arc
							(start 0.1778 0.2794)
							(mid 0.249642 0.249642)
							(end 0.2794 0.1778)
						)
						(arc
							(start 0.2794 -0.1778)
							(mid 0.249642 -0.249642)
							(end 0.1778 -0.2794)
						)
					)
					(width 0)
					(fill yes)
				)
			)
		)
	)
	(footprint ""
		(layer "F.Cu")
		(at 158.369 -108.966 90)
		(property "Reference" "SC1208"
			(at 0 0 90)
			(layer "F.SilkS")
			(hide yes)
			(effects
				(font
					(size 1.27 1.27)
				)
			)
		)
		(property "Value" "SC10U6D3V5KX-4GP"
			(at -0.0762 -6.1214 90)
			(unlocked yes)
			(layer "F.Fab")
			(hide yes)
			(effects
				(font
					(size 1.016 1.016)
					(thickness 0.1524)
				)
			)
		)
		(property "Device Type" "C805H58"
			(at -0.0762 -8.1534 90)
			(unlocked yes)
			(layer "F.Fab")
			(hide yes)
			(effects
				(font
					(size 1.016 1.016)
					(thickness 0.1524)
				)
			)
		)
		(duplicate_pad_numbers_are_jumpers no)
		(fp_line
			(start 0.635 0)
			(end -0.635 0)
			(stroke
				(width 0.508)
				(type default)
			)
			(layer "F.SilkS")
		)
		(fp_rect
			(start -0.9652 1.778)
			(end 0.9652 -1.778)
			(stroke
				(width 0)
				(type default)
			)
			(fill no)
			(layer "F.CrtYd")
		)
		(fp_poly
			(pts
				(xy -0.9652 -1.778) (xy 0.9652 -1.778) (xy 0.9652 1.778) (xy -0.9652 1.778)
			)
			(stroke
				(width 0)
				(type default)
			)
			(fill no)
			(layer "F.Fab")
		)
		(pad "1" smd rect
			(at 0 -0.9652 90)
			(size 1.397 1.143)
			(layers "F.Cu" "F.Mask" "F.Paste")
			(net "P0V9_E")
		)
		(pad "2" smd rect
			(at 0 0.9652 90)
			(size 1.397 1.143)
			(layers "F.Cu" "F.Mask" "F.Paste")
			(net "GND")
		)
	)
	(footprint ""
		(layer "F.Cu")
		(at 86.49716 -33.02 -90)
		(property "Reference" "SC879"
			(at 0 0 270)
			(layer "F.SilkS")
			(hide yes)
			(effects
				(font
					(size 1.27 1.27)
				)
			)
		)
		(property "Value" "SCD01U10V1KX-GP"
			(at -2.8321 -1.7399 270)
			(unlocked yes)
			(layer "F.Fab")
			(hide yes)
			(effects
				(font
					(size 1.016 1.016)
					(thickness 0.1524)
				)
			)
		)
		(property "Device Type" "C0201H13"
			(at -2.8321 -3.2639 270)
			(unlocked yes)
			(layer "F.Fab")
			(hide yes)
			(effects
				(font
					(size 1.016 1.016)
					(thickness 0.1524)
				)
			)
		)
		(duplicate_pad_numbers_are_jumpers no)
		(fp_rect
			(start -0.2794 0.6477)
			(end 0.2794 -0.6477)
			(stroke
				(width 0)
				(type default)
			)
			(fill no)
			(layer "F.CrtYd")
		)
		(fp_rect
			(start -0.2794 0.6477)
			(end 0.2794 -0.6477)
			(stroke
				(width 0)
				(type default)
			)
			(fill no)
			(layer "F.Fab")
		)
		(pad "1" smd custom
			(at 0 -0.2794 270)
			(size 0.0762 0.0762)
			(layers "F.Cu" "F.Mask" "F.Paste")
			(net "SAS3008_RAID_TX_C_N0")
			(options
				(clearance outline)
				(anchor circle)
			)
			(primitives
				(gr_poly
					(pts
						(arc
							(start 0.1524 -0.127)
							(mid 0.137521 -0.162921)
							(end 0.1016 -0.1778)
						)
						(arc
							(start -0.1016 -0.1778)
							(mid -0.137521 -0.162921)
							(end -0.1524 -0.127)
						)
						(arc
							(start -0.1524 0.127)
							(mid -0.137521 0.162921)
							(end -0.1016 0.1778)
						)
						(arc
							(start 0.1016 0.1778)
							(mid 0.137521 0.162921)
							(end 0.1524 0.127)
						)
					)
					(width 0)
					(fill yes)
				)
			)
		)
		(pad "2" smd custom
			(at 0 0.2794 270)
			(size 0.0762 0.0762)
			(layers "F.Cu" "F.Mask" "F.Paste")
			(net "SAS3008_RAID_TX_N0")
			(options
				(clearance outline)
				(anchor circle)
			)
			(primitives
				(gr_poly
					(pts
						(arc
							(start 0.1524 -0.127)
							(mid 0.137521 -0.162921)
							(end 0.1016 -0.1778)
						)
						(arc
							(start -0.1016 -0.1778)
							(mid -0.137521 -0.162921)
							(end -0.1524 -0.127)
						)
						(arc
							(start -0.1524 0.127)
							(mid -0.137521 0.162921)
							(end -0.1016 0.1778)
						)
						(arc
							(start 0.1016 0.1778)
							(mid 0.137521 0.162921)
							(end 0.1524 0.127)
						)
					)
					(width 0)
					(fill yes)
				)
			)
		)
	)
	(footprint ""
		(layer "F.Cu")
		(at 131.318 -87.884 90)
		(property "Reference" "SC1263"
			(at 0 0 90)
			(layer "F.SilkS")
			(hide yes)
			(effects
				(font
					(size 1.27 1.27)
				)
			)
		)
		(property "Value" "SCD01U10V1KX-GP"
			(at -2.8321 -1.7399 90)
			(unlocked yes)
			(layer "F.Fab")
			(hide yes)
			(effects
				(font
					(size 1.016 1.016)
					(thickness 0.1524)
				)
			)
		)
		(property "Device Type" "C0201H13"
			(at -2.8321 -3.2639 90)
			(unlocked yes)
			(layer "F.Fab")
			(hide yes)
			(effects
				(font
					(size 1.016 1.016)
					(thickness 0.1524)
				)
			)
		)
		(duplicate_pad_numbers_are_jumpers no)
		(fp_rect
			(start -0.2794 0.6477)
			(end 0.2794 -0.6477)
			(stroke
				(width 0)
				(type default)
			)
			(fill no)
			(layer "F.CrtYd")
		)
		(fp_rect
			(start -0.2794 0.6477)
			(end 0.2794 -0.6477)
			(stroke
				(width 0)
				(type default)
			)
			(fill no)
			(layer "F.Fab")
		)
		(pad "1" smd custom
			(at 0 -0.2794 90)
			(size 0.0762 0.0762)
			(layers "F.Cu" "F.Mask" "F.Paste")
			(net "3X24_SAS_TX16_N")
			(options
				(clearance outline)
				(anchor circle)
			)
			(primitives
				(gr_poly
					(pts
						(arc
							(start 0.1524 -0.127)
							(mid 0.137521 -0.162921)
							(end 0.1016 -0.1778)
						)
						(arc
							(start -0.1016 -0.1778)
							(mid -0.137521 -0.162921)
							(end -0.1524 -0.127)
						)
						(arc
							(start -0.1524 0.127)
							(mid -0.137521 0.162921)
							(end -0.1016 0.1778)
						)
						(arc
							(start 0.1016 0.1778)
							(mid 0.137521 0.162921)
							(end 0.1524 0.127)
						)
					)
					(width 0)
					(fill yes)
				)
			)
		)
		(pad "2" smd custom
			(at 0 0.2794 90)
			(size 0.0762 0.0762)
			(layers "F.Cu" "F.Mask" "F.Paste")
			(net "SAS_EXP2CONN_TX_N_20")
			(options
				(clearance outline)
				(anchor circle)
			)
			(primitives
				(gr_poly
					(pts
						(arc
							(start 0.1524 -0.127)
							(mid 0.137521 -0.162921)
							(end 0.1016 -0.1778)
						)
						(arc
							(start -0.1016 -0.1778)
							(mid -0.137521 -0.162921)
							(end -0.1524 -0.127)
						)
						(arc
							(start -0.1524 0.127)
							(mid -0.137521 0.162921)
							(end -0.1016 0.1778)
						)
						(arc
							(start 0.1016 0.1778)
							(mid 0.137521 0.162921)
							(end 0.1524 0.127)
						)
					)
					(width 0)
					(fill yes)
				)
			)
		)
	)
	(footprint ""
		(layer "F.Cu")
		(at 335.661 -217.3605)
		(property "Reference" "R5303"
			(at 0 0 0)
			(layer "F.SilkS")
			(hide yes)
			(effects
				(font
					(size 1.27 1.27)
				)
			)
		)
		(property "Value" "0R2J-2-GP"
			(at 0.064008 -3.993896 0)
			(unlocked yes)
			(layer "F.Fab")
			(hide yes)
			(effects
				(font
					(size 1.016 1.016)
					(thickness 0.1524)
				)
			)
		)
		(property "Device Type" "R402H16"
			(at 0.064008 -5.517896 0)
			(unlocked yes)
			(layer "F.Fab")
			(hide yes)
			(effects
				(font
					(size 1.016 1.016)
					(thickness 0.1524)
				)
			)
		)
		(duplicate_pad_numbers_are_jumpers no)
		(fp_line
			(start -0.508 -0.9398)
			(end -0.508 0.9398)
			(stroke
				(width 0.1524)
				(type default)
			)
			(layer "F.SilkS")
		)
		(fp_line
			(start 0.508 -0.9398)
			(end -0.508 -0.9398)
			(stroke
				(width 0.1524)
				(type default)
			)
			(layer "F.SilkS")
		)
		(fp_rect
			(start -0.508 0.9398)
			(end 0.508 -0.9398)
			(stroke
				(width 0)
				(type default)
			)
			(fill no)
			(layer "F.CrtYd")
		)
		(fp_rect
			(start -0.508 0.9398)
			(end 0.508 -0.9398)
			(stroke
				(width 0)
				(type default)
			)
			(fill no)
			(layer "F.Fab")
		)
		(pad "1" smd custom
			(at 0 -0.4445)
			(size 0.1397 0.1397)
			(layers "F.Cu" "F.Mask" "F.Paste")
			(net "VOL_SEN_SCL")
			(options
				(clearance outline)
				(anchor circle)
			)
			(primitives
				(gr_poly
					(pts
						(arc
							(start -0.1778 -0.2794)
							(mid -0.249642 -0.249642)
							(end -0.2794 -0.1778)
						)
						(arc
							(start -0.2794 0.1778)
							(mid -0.249642 0.249642)
							(end -0.1778 0.2794)
						)
						(arc
							(start 0.1778 0.2794)
							(mid 0.249642 0.249642)
							(end 0.2794 0.1778)
						)
						(arc
							(start 0.2794 -0.1778)
							(mid 0.249642 -0.249642)
							(end 0.1778 -0.2794)
						)
					)
					(width 0)
					(fill yes)
				)
			)
		)
		(pad "2" smd custom
			(at 0 0.4445)
			(size 0.1397 0.1397)
			(layers "F.Cu" "F.Mask" "F.Paste")
			(net "BMC_I2C_SCL_10")
			(options
				(clearance outline)
				(anchor circle)
			)
			(primitives
				(gr_poly
					(pts
						(arc
							(start -0.1778 -0.2794)
							(mid -0.249642 -0.249642)
							(end -0.2794 -0.1778)
						)
						(arc
							(start -0.2794 0.1778)
							(mid -0.249642 0.249642)
							(end -0.1778 0.2794)
						)
						(arc
							(start 0.1778 0.2794)
							(mid 0.249642 0.249642)
							(end 0.2794 0.1778)
						)
						(arc
							(start 0.2794 -0.1778)
							(mid 0.249642 -0.249642)
							(end 0.1778 -0.2794)
						)
					)
					(width 0)
					(fill yes)
				)
			)
		)
	)
	(footprint ""
		(layer "F.Cu")
		(at 163.322 -154.9146 -90)
		(property "Reference" "SU63"
			(at 0 0 270)
			(layer "F.SilkS")
			(hide yes)
			(effects
				(font
					(size 1.27 1.27)
				)
			)
		)
		(property "Value" "2N7002DW-7F-GP"
			(at -2.3622 -8.2042 270)
			(unlocked yes)
			(layer "F.Fab")
			(hide yes)
			(effects
				(font
					(size 1.016 1.016)
					(thickness 0.1524)
				)
			)
		)
		(property "Device Type" "SOT-363H44"
			(at -2.3622 -10.1092 270)
			(unlocked yes)
			(layer "F.Fab")
			(hide yes)
			(effects
				(font
					(size 1.016 1.016)
					(thickness 0.1524)
				)
			)
		)
		(duplicate_pad_numbers_are_jumpers no)
		(fp_line
			(start -1.4478 1.7018)
			(end 1.4478 1.7018)
			(stroke
				(width 0.1524)
				(type default)
			)
			(layer "F.SilkS")
		)
		(fp_line
			(start 1.4478 1.7018)
			(end 1.4478 -1.7018)
			(stroke
				(width 0.1524)
				(type default)
			)
			(layer "F.SilkS")
		)
		(fp_line
			(start -1.27 1.524)
			(end -1.27 0.6604)
			(stroke
				(width 0.4826)
				(type default)
			)
			(layer "F.SilkS")
		)
		(fp_line
			(start -1.4478 -1.7018)
			(end -1.4478 1.7018)
			(stroke
				(width 0.1524)
				(type default)
			)
			(layer "F.SilkS")
		)
		(fp_line
			(start 1.4478 -1.7018)
			(end -1.4478 -1.7018)
			(stroke
				(width 0.1524)
				(type default)
			)
			(layer "F.SilkS")
		)
		(fp_poly
			(pts
				(xy -1.524 -1.778) (xy 1.524 -1.778) (xy 1.524 1.778) (xy -1.524 1.778)
			)
			(stroke
				(width 0)
				(type default)
			)
			(fill no)
			(layer "F.CrtYd")
		)
		(fp_poly
			(pts
				(xy -1.524 -1.778) (xy 1.524 -1.778) (xy 1.524 1.778) (xy -1.524 1.778)
			)
			(stroke
				(width 0)
				(type default)
			)
			(fill no)
			(layer "F.Fab")
		)
		(pad "1" smd rect
			(at -0.65024 0.9398 270)
			(size 0.4064 1.016)
			(layers "F.Cu" "F.Mask" "F.Paste")
			(net "IOC_P3V3_R_SCL_14")
		)
		(pad "2" smd rect
			(at 0 0.9398 270)
			(size 0.4064 1.016)
			(layers "F.Cu" "F.Mask" "F.Paste")
			(net "PMU_PLTRST_N")
		)
		(pad "3" smd rect
			(at 0.65024 0.9398 270)
			(size 0.4064 1.016)
			(layers "F.Cu" "F.Mask" "F.Paste")
			(net "EXP_IOC_BMC_R_SDA_14")
		)
		(pad "4" smd rect
			(at 0.65024 -0.9398 270)
			(size 0.4064 1.016)
			(layers "F.Cu" "F.Mask" "F.Paste")
			(net "IOC_P3V3_R_SDA_14")
		)
		(pad "5" smd rect
			(at 0 -0.9398 270)
			(size 0.4064 1.016)
			(layers "F.Cu" "F.Mask" "F.Paste")
			(net "PMU_PLTRST_N")
		)
		(pad "6" smd rect
			(at -0.65024 -0.9398 270)
			(size 0.4064 1.016)
			(layers "F.Cu" "F.Mask" "F.Paste")
			(net "EXP_IOC_BMC_R_SCL_14")
		)
	)
	(footprint ""
		(layer "F.Cu")
		(at 88.138 -27.159966 180)
		(property "Reference" "SR588"
			(at 0 0 180)
			(layer "F.SilkS")
			(hide yes)
			(effects
				(font
					(size 1.27 1.27)
				)
			)
		)
		(property "Value" "0R2J-2-GP"
			(at 0.064008 -3.993896 180)
			(unlocked yes)
			(layer "F.Fab")
			(hide yes)
			(effects
				(font
					(size 1.016 1.016)
					(thickness 0.1524)
				)
			)
		)
		(property "Device Type" "R402H16"
			(at 0.064008 -5.517896 180)
			(unlocked yes)
			(layer "F.Fab")
			(hide yes)
			(effects
				(font
					(size 1.016 1.016)
					(thickness 0.1524)
				)
			)
		)
		(duplicate_pad_numbers_are_jumpers no)
		(fp_line
			(start 0.508 -0.9398)
			(end -0.508 -0.9398)
			(stroke
				(width 0.1524)
				(type default)
			)
			(layer "F.SilkS")
		)
		(fp_line
			(start -0.508 -0.9398)
			(end -0.508 0.9398)
			(stroke
				(width 0.1524)
				(type default)
			)
			(layer "F.SilkS")
		)
		(fp_rect
			(start -0.508 0.9398)
			(end 0.508 -0.9398)
			(stroke
				(width 0)
				(type default)
			)
			(fill no)
			(layer "F.CrtYd")
		)
		(fp_rect
			(start -0.508 0.9398)
			(end 0.508 -0.9398)
			(stroke
				(width 0)
				(type default)
			)
			(fill no)
			(layer "F.Fab")
		)
		(pad "1" smd custom
			(at 0 -0.4445 180)
			(size 0.1397 0.1397)
			(layers "F.Cu" "F.Mask" "F.Paste")
			(net "CLK_100M_PCIE_SAS_C_N")
			(options
				(clearance outline)
				(anchor circle)
			)
			(primitives
				(gr_poly
					(pts
						(arc
							(start -0.1778 -0.2794)
							(mid -0.249642 -0.249642)
							(end -0.2794 -0.1778)
						)
						(arc
							(start -0.2794 0.1778)
							(mid -0.249642 0.249642)
							(end -0.1778 0.2794)
						)
						(arc
							(start 0.1778 0.2794)
							(mid 0.249642 0.249642)
							(end 0.2794 0.1778)
						)
						(arc
							(start 0.2794 -0.1778)
							(mid 0.249642 -0.249642)
							(end 0.1778 -0.2794)
						)
					)
					(width 0)
					(fill yes)
				)
			)
		)
		(pad "2" smd custom
			(at 0 0.4445 180)
			(size 0.1397 0.1397)
			(layers "F.Cu" "F.Mask" "F.Paste")
			(net "CLK_100M_PCIE_N")
			(options
				(clearance outline)
				(anchor circle)
			)
			(primitives
				(gr_poly
					(pts
						(arc
							(start -0.1778 -0.2794)
							(mid -0.249642 -0.249642)
							(end -0.2794 -0.1778)
						)
						(arc
							(start -0.2794 0.1778)
							(mid -0.249642 0.249642)
							(end -0.1778 0.2794)
						)
						(arc
							(start 0.1778 0.2794)
							(mid 0.249642 0.249642)
							(end 0.2794 0.1778)
						)
						(arc
							(start 0.2794 -0.1778)
							(mid 0.249642 -0.249642)
							(end 0.1778 -0.2794)
						)
					)
					(width 0)
					(fill yes)
				)
			)
		)
	)
)
